(kicad_pcb
	(version 20260206)
	(generator "pcbnew")
	(generator_version "10.0")
	(general
		(thickness 1.6)
		(legacy_teardrops no)
	)
	(paper "A4")
	(title_block
		(title "04192023_DAF0TMB3IC0_F0TG_MB_C_brd_V02_OCP.brd")
		(comment 1 "Grand Teton / footprints 532-538 of 8354")
	)
	(layers
		(0 "F.Cu" signal "TOP")
		(4 "In1.Cu" signal "GND")
		(6 "In2.Cu" signal "IN1")
		(8 "In3.Cu" signal "GND1")
		(10 "In4.Cu" signal "IN2")
		(12 "In5.Cu" signal "GND2")
		(14 "In6.Cu" signal "IN3")
		(16 "In7.Cu" signal "GND3")
		(18 "In8.Cu" signal "VCC")
		(20 "In9.Cu" signal "VCC1")
		(22 "In10.Cu" signal "GND4")
		(24 "In11.Cu" signal "IN4")
		(26 "In12.Cu" signal "GND5")
		(28 "In13.Cu" signal "IN5")
		(30 "In14.Cu" signal "GND6")
		(32 "In15.Cu" signal "IN6")
		(34 "In16.Cu" signal "GND7")
		(2 "B.Cu" signal "BOTTOM")
		(9 "F.Adhes" user "F.Adhesive")
		(11 "B.Adhes" user "B.Adhesive")
		(13 "F.Paste" user "Package Geometry/Pastemask Top")
		(15 "B.Paste" user "Package Geometry/Pastemask Bottom")
		(5 "F.SilkS" user "Ref Des/Silkscreen Top")
		(7 "B.SilkS" user "Ref Des/Silkscreen Bottom")
		(1 "F.Mask" user "Board Geometry/Soldermask Top")
		(3 "B.Mask" user "Board Geometry/Soldermask Bottom")
		(17 "Dwgs.User" user "User.Drawings")
		(19 "Cmts.User" user "User.Comments")
		(21 "Eco1.User" user "User.Eco1")
		(23 "Eco2.User" user "User.Eco2")
		(25 "Edge.Cuts" user "Board Geometry/Outline")
		(27 "Margin" user)
		(31 "F.CrtYd" user "Package Geometry/Place Bound Top")
		(29 "B.CrtYd" user "Package Geometry/Place Bound Bottom")
		(35 "F.Fab" user "Ref Des/Assembly Top")
		(33 "B.Fab" user "Ref Des/Assembly Bottom")
	)
	(footprint ""
		(layer "F.Cu")
		(at 115.277138 -261.748016 -90)
		(property "Reference" "C2485"
			(at 0 0 270)
			(layer "F.SilkS")
			(hide yes)
			(effects
				(font
					(size 1.27 1.27)
				)
			)
		)
		(property "Value" ""
			(at 0 0 270)
			(layer "F.Fab")
			(effects
				(font
					(size 1.27 1.27)
				)
			)
		)
		(duplicate_pad_numbers_are_jumpers no)
		(fp_line
			(start -0.7874 0.4064)
			(end -0.7874 -0.4064)
			(stroke
				(width 0.1524)
				(type default)
			)
			(layer "F.SilkS")
		)
		(fp_line
			(start 0.7874 0.4064)
			(end -0.7874 0.4064)
			(stroke
				(width 0.1524)
				(type default)
			)
			(layer "F.SilkS")
		)
		(fp_line
			(start -0.7874 -0.4064)
			(end 0.7874 -0.4064)
			(stroke
				(width 0.1524)
				(type default)
			)
			(layer "F.SilkS")
		)
		(fp_line
			(start 0.7874 -0.4064)
			(end 0.7874 0.4064)
			(stroke
				(width 0.1524)
				(type default)
			)
			(layer "F.SilkS")
		)
		(fp_line
			(start -0.67945 0.3048)
			(end -0.67945 -0.305054)
			(stroke
				(width 0.1)
				(type default)
			)
			(layer "F.Fab")
		)
		(fp_line
			(start -0.12065 0.3048)
			(end -0.67945 0.3048)
			(stroke
				(width 0.1)
				(type default)
			)
			(layer "F.Fab")
		)
		(fp_line
			(start 0.120396 0.3048)
			(end 0.120396 0.2794)
			(stroke
				(width 0.1)
				(type default)
			)
			(layer "F.Fab")
		)
		(fp_line
			(start 0.67945 0.3048)
			(end 0.120396 0.3048)
			(stroke
				(width 0.1)
				(type default)
			)
			(layer "F.Fab")
		)
		(fp_line
			(start -0.12065 0.2794)
			(end -0.12065 0.3048)
			(stroke
				(width 0.1)
				(type default)
			)
			(layer "F.Fab")
		)
		(fp_line
			(start 0.120396 0.2794)
			(end -0.12065 0.2794)
			(stroke
				(width 0.1)
				(type default)
			)
			(layer "F.Fab")
		)
		(fp_line
			(start -0.12065 -0.2794)
			(end 0.12065 -0.2794)
			(stroke
				(width 0.1)
				(type default)
			)
			(layer "F.Fab")
		)
		(fp_line
			(start 0.12065 -0.2794)
			(end 0.12065 -0.3048)
			(stroke
				(width 0.1)
				(type default)
			)
			(layer "F.Fab")
		)
		(fp_line
			(start 0.12065 -0.3048)
			(end 0.67945 -0.3048)
			(stroke
				(width 0.1)
				(type default)
			)
			(layer "F.Fab")
		)
		(fp_line
			(start 0.67945 -0.3048)
			(end 0.67945 0.3048)
			(stroke
				(width 0.1)
				(type default)
			)
			(layer "F.Fab")
		)
		(fp_line
			(start -0.67945 -0.305054)
			(end -0.12065 -0.305054)
			(stroke
				(width 0.1)
				(type default)
			)
			(layer "F.Fab")
		)
		(fp_line
			(start -0.12065 -0.305054)
			(end -0.12065 -0.2794)
			(stroke
				(width 0.1)
				(type default)
			)
			(layer "F.Fab")
		)
		(pad "1" smd circle
			(at -0.40005 0 270)
			(size 0 0)
			(layers "F.Cu" "F.Mask" "F.Paste")
			(net "PVDD11_S3_P1")
		)
		(pad "2" smd circle
			(at 0.40005 0 270)
			(size 0 0)
			(layers "F.Cu" "F.Mask" "F.Paste")
			(net "GND")
		)
	)
	(footprint ""
		(layer "F.Cu")
		(at 118.491 -424.688 180)
		(property "Reference" "R3456"
			(at 0 0 180)
			(layer "F.SilkS")
			(hide yes)
			(effects
				(font
					(size 1.27 1.27)
				)
			)
		)
		(property "Value" ""
			(at 0 0 180)
			(layer "F.Fab")
			(effects
				(font
					(size 1.27 1.27)
				)
			)
		)
		(duplicate_pad_numbers_are_jumpers no)
		(fp_line
			(start 0.7874 0.4064)
			(end -0.7874 0.4064)
			(stroke
				(width 0.1524)
				(type default)
			)
			(layer "F.SilkS")
		)
		(fp_line
			(start 0.7874 -0.4064)
			(end 0.7874 0.4064)
			(stroke
				(width 0.1524)
				(type default)
			)
			(layer "F.SilkS")
		)
		(fp_line
			(start -0.7874 0.4064)
			(end -0.7874 -0.4064)
			(stroke
				(width 0.1524)
				(type default)
			)
			(layer "F.SilkS")
		)
		(fp_line
			(start -0.7874 -0.4064)
			(end 0.7874 -0.4064)
			(stroke
				(width 0.1524)
				(type default)
			)
			(layer "F.SilkS")
		)
		(fp_line
			(start 0.67945 0.3048)
			(end 0.120396 0.3048)
			(stroke
				(width 0.1)
				(type default)
			)
			(layer "F.Fab")
		)
		(fp_line
			(start 0.67945 -0.3048)
			(end 0.67945 0.3048)
			(stroke
				(width 0.1)
				(type default)
			)
			(layer "F.Fab")
		)
		(fp_line
			(start 0.12065 -0.2794)
			(end 0.12065 -0.3048)
			(stroke
				(width 0.1)
				(type default)
			)
			(layer "F.Fab")
		)
		(fp_line
			(start 0.12065 -0.3048)
			(end 0.67945 -0.3048)
			(stroke
				(width 0.1)
				(type default)
			)
			(layer "F.Fab")
		)
		(fp_line
			(start 0.120396 0.3048)
			(end 0.120396 0.2794)
			(stroke
				(width 0.1)
				(type default)
			)
			(layer "F.Fab")
		)
		(fp_line
			(start 0.120396 0.2794)
			(end -0.12065 0.2794)
			(stroke
				(width 0.1)
				(type default)
			)
			(layer "F.Fab")
		)
		(fp_line
			(start -0.12065 0.3048)
			(end -0.67945 0.3048)
			(stroke
				(width 0.1)
				(type default)
			)
			(layer "F.Fab")
		)
		(fp_line
			(start -0.12065 0.2794)
			(end -0.12065 0.3048)
			(stroke
				(width 0.1)
				(type default)
			)
			(layer "F.Fab")
		)
		(fp_line
			(start -0.12065 -0.2794)
			(end 0.12065 -0.2794)
			(stroke
				(width 0.1)
				(type default)
			)
			(layer "F.Fab")
		)
		(fp_line
			(start -0.12065 -0.305054)
			(end -0.12065 -0.2794)
			(stroke
				(width 0.1)
				(type default)
			)
			(layer "F.Fab")
		)
		(fp_line
			(start -0.67945 0.3048)
			(end -0.67945 -0.305054)
			(stroke
				(width 0.1)
				(type default)
			)
			(layer "F.Fab")
		)
		(fp_line
			(start -0.67945 -0.305054)
			(end -0.12065 -0.305054)
			(stroke
				(width 0.1)
				(type default)
			)
			(layer "F.Fab")
		)
		(pad "1" smd circle
			(at -0.40005 0 180)
			(size 0 0)
			(layers "F.Cu" "F.Mask" "F.Paste")
			(net "P3V3_AUX")
		)
		(pad "2" smd circle
			(at 0.40005 0 180)
			(size 0 0)
			(layers "F.Cu" "F.Mask" "F.Paste")
			(net "GPU_BASE_STBY_EN_BUF_R")
		)
	)
	(footprint ""
		(layer "F.Cu")
		(at 151.13 -113.157 180)
		(property "Reference" "R71"
			(at 0 0 180)
			(layer "F.SilkS")
			(hide yes)
			(effects
				(font
					(size 1.27 1.27)
				)
			)
		)
		(property "Value" ""
			(at 0 0 180)
			(layer "F.Fab")
			(effects
				(font
					(size 1.27 1.27)
				)
			)
		)
		(duplicate_pad_numbers_are_jumpers no)
		(fp_line
			(start 0.7874 0.4064)
			(end -0.7874 0.4064)
			(stroke
				(width 0.1524)
				(type default)
			)
			(layer "F.SilkS")
		)
		(fp_line
			(start 0.7874 -0.4064)
			(end 0.7874 0.4064)
			(stroke
				(width 0.1524)
				(type default)
			)
			(layer "F.SilkS")
		)
		(fp_line
			(start -0.7874 0.4064)
			(end -0.7874 -0.4064)
			(stroke
				(width 0.1524)
				(type default)
			)
			(layer "F.SilkS")
		)
		(fp_line
			(start -0.7874 -0.4064)
			(end 0.7874 -0.4064)
			(stroke
				(width 0.1524)
				(type default)
			)
			(layer "F.SilkS")
		)
		(fp_line
			(start 0.67945 0.3048)
			(end 0.120396 0.3048)
			(stroke
				(width 0.1)
				(type default)
			)
			(layer "F.Fab")
		)
		(fp_line
			(start 0.67945 -0.3048)
			(end 0.67945 0.3048)
			(stroke
				(width 0.1)
				(type default)
			)
			(layer "F.Fab")
		)
		(fp_line
			(start 0.12065 -0.2794)
			(end 0.12065 -0.3048)
			(stroke
				(width 0.1)
				(type default)
			)
			(layer "F.Fab")
		)
		(fp_line
			(start 0.12065 -0.3048)
			(end 0.67945 -0.3048)
			(stroke
				(width 0.1)
				(type default)
			)
			(layer "F.Fab")
		)
		(fp_line
			(start 0.120396 0.3048)
			(end 0.120396 0.2794)
			(stroke
				(width 0.1)
				(type default)
			)
			(layer "F.Fab")
		)
		(fp_line
			(start 0.120396 0.2794)
			(end -0.12065 0.2794)
			(stroke
				(width 0.1)
				(type default)
			)
			(layer "F.Fab")
		)
		(fp_line
			(start -0.12065 0.3048)
			(end -0.67945 0.3048)
			(stroke
				(width 0.1)
				(type default)
			)
			(layer "F.Fab")
		)
		(fp_line
			(start -0.12065 0.2794)
			(end -0.12065 0.3048)
			(stroke
				(width 0.1)
				(type default)
			)
			(layer "F.Fab")
		)
		(fp_line
			(start -0.12065 -0.2794)
			(end 0.12065 -0.2794)
			(stroke
				(width 0.1)
				(type default)
			)
			(layer "F.Fab")
		)
		(fp_line
			(start -0.12065 -0.305054)
			(end -0.12065 -0.2794)
			(stroke
				(width 0.1)
				(type default)
			)
			(layer "F.Fab")
		)
		(fp_line
			(start -0.67945 0.3048)
			(end -0.67945 -0.305054)
			(stroke
				(width 0.1)
				(type default)
			)
			(layer "F.Fab")
		)
		(fp_line
			(start -0.67945 -0.305054)
			(end -0.12065 -0.305054)
			(stroke
				(width 0.1)
				(type default)
			)
			(layer "F.Fab")
		)
		(pad "1" smd circle
			(at -0.40005 0 180)
			(size 0 0)
			(layers "F.Cu" "F.Mask" "F.Paste")
			(net "SCM_IRQ_R_N")
		)
		(pad "2" smd circle
			(at 0.40005 0 180)
			(size 0 0)
			(layers "F.Cu" "F.Mask" "F.Paste")
			(net "SCM_IRQ_N")
		)
	)
	(footprint ""
		(layer "F.Cu")
		(at 70.662546 -385.09448 180)
		(property "Reference" "L27"
			(at 0 0 180)
			(layer "F.SilkS")
			(hide yes)
			(effects
				(font
					(size 1.27 1.27)
				)
			)
		)
		(property "Value" ""
			(at 0 0 180)
			(layer "F.Fab")
			(effects
				(font
					(size 1.27 1.27)
				)
			)
		)
		(duplicate_pad_numbers_are_jumpers no)
		(fp_line
			(start 0.762 0.381)
			(end -0.762 0.381)
			(stroke
				(width 0.1524)
				(type default)
			)
			(layer "F.SilkS")
		)
		(fp_line
			(start 0.762 -0.381)
			(end 0.762 0.381)
			(stroke
				(width 0.1524)
				(type default)
			)
			(layer "F.SilkS")
		)
		(fp_line
			(start -0.762 0.381)
			(end -0.762 -0.381)
			(stroke
				(width 0.1524)
				(type default)
			)
			(layer "F.SilkS")
		)
		(fp_line
			(start -0.762 -0.381)
			(end 0.762 -0.381)
			(stroke
				(width 0.1524)
				(type default)
			)
			(layer "F.SilkS")
		)
		(fp_line
			(start 0.680466 0.306324)
			(end 0.118364 0.306324)
			(stroke
				(width 0.1)
				(type default)
			)
			(layer "F.Fab")
		)
		(fp_line
			(start 0.680466 -0.306324)
			(end 0.680466 0.306324)
			(stroke
				(width 0.1)
				(type default)
			)
			(layer "F.Fab")
		)
		(fp_line
			(start 0.118872 -0.2794)
			(end 0.118872 -0.306324)
			(stroke
				(width 0.1)
				(type default)
			)
			(layer "F.Fab")
		)
		(fp_line
			(start 0.118872 -0.306324)
			(end 0.680466 -0.306324)
			(stroke
				(width 0.1)
				(type default)
			)
			(layer "F.Fab")
		)
		(fp_line
			(start 0.118364 0.306324)
			(end 0.118364 0.2794)
			(stroke
				(width 0.1)
				(type default)
			)
			(layer "F.Fab")
		)
		(fp_line
			(start 0.118364 0.2794)
			(end -0.119634 0.2794)
			(stroke
				(width 0.1)
				(type default)
			)
			(layer "F.Fab")
		)
		(fp_line
			(start -0.118364 -0.2794)
			(end 0.118872 -0.2794)
			(stroke
				(width 0.1)
				(type default)
			)
			(layer "F.Fab")
		)
		(fp_line
			(start -0.118364 -0.307086)
			(end -0.118364 -0.2794)
			(stroke
				(width 0.1)
				(type default)
			)
			(layer "F.Fab")
		)
		(fp_line
			(start -0.119634 0.30607)
			(end -0.681736 0.30607)
			(stroke
				(width 0.1)
				(type default)
			)
			(layer "F.Fab")
		)
		(fp_line
			(start -0.119634 0.2794)
			(end -0.119634 0.30607)
			(stroke
				(width 0.1)
				(type default)
			)
			(layer "F.Fab")
		)
		(fp_line
			(start -0.681736 0.30607)
			(end -0.681736 -0.307086)
			(stroke
				(width 0.1)
				(type default)
			)
			(layer "F.Fab")
		)
		(fp_line
			(start -0.681736 -0.307086)
			(end -0.118364 -0.307086)
			(stroke
				(width 0.1)
				(type default)
			)
			(layer "F.Fab")
		)
		(pad "1" smd rect
			(at -0.40005 0)
			(size 0.4572 0.508)
			(layers "F.Cu" "F.Mask" "F.Paste")
			(net "P1V8_CPU1_RT_1D")
		)
		(pad "2" smd rect
			(at 0.40005 0)
			(size 0.4572 0.508)
			(layers "F.Cu" "F.Mask" "F.Paste")
			(net "P1V8_CPU1_RT0_1A_1D")
		)
	)
	(footprint ""
		(layer "F.Cu")
		(at 51.498754 -370.57203 -90)
		(property "Reference" "C825"
			(at 0 0 270)
			(layer "F.SilkS")
			(hide yes)
			(effects
				(font
					(size 1.27 1.27)
				)
			)
		)
		(property "Value" ""
			(at 0 0 270)
			(layer "F.Fab")
			(effects
				(font
					(size 1.27 1.27)
				)
			)
		)
		(duplicate_pad_numbers_are_jumpers no)
		(fp_line
			(start -0.299974 0.150114)
			(end -0.299974 -0.150114)
			(stroke
				(width 0.1)
				(type default)
			)
			(layer "F.Fab")
		)
		(fp_line
			(start 0.299974 0.150114)
			(end -0.299974 0.150114)
			(stroke
				(width 0.1)
				(type default)
			)
			(layer "F.Fab")
		)
		(fp_line
			(start -0.299974 -0.150114)
			(end 0.299974 -0.150114)
			(stroke
				(width 0.1)
				(type default)
			)
			(layer "F.Fab")
		)
		(fp_line
			(start 0.299974 -0.150114)
			(end 0.299974 0.150114)
			(stroke
				(width 0.1)
				(type default)
			)
			(layer "F.Fab")
		)
		(pad "1" smd rect
			(at -0.2667 0 270)
			(size 0.3048 0.381)
			(layers "F.Cu" "F.Mask" "F.Paste")
			(net "P5E_CPU1_P0_TX_C_DP<6>")
		)
		(pad "2" smd rect
			(at 0.2667 0 270)
			(size 0.3048 0.381)
			(layers "F.Cu" "F.Mask" "F.Paste")
			(net "P5E_CPU1_P0_TX_DP<6>")
		)
	)
	(footprint ""
		(layer "F.Cu")
		(at 197.269608 -114.641376 180)
		(property "Reference" "R199"
			(at 0 0 180)
			(layer "F.SilkS")
			(hide yes)
			(effects
				(font
					(size 1.27 1.27)
				)
			)
		)
		(property "Value" ""
			(at 0 0 180)
			(layer "F.Fab")
			(effects
				(font
					(size 1.27 1.27)
				)
			)
		)
		(duplicate_pad_numbers_are_jumpers no)
		(fp_line
			(start 0.7874 0.4064)
			(end -0.7874 0.4064)
			(stroke
				(width 0.1524)
				(type default)
			)
			(layer "F.SilkS")
		)
		(fp_line
			(start 0.7874 -0.4064)
			(end 0.7874 0.4064)
			(stroke
				(width 0.1524)
				(type default)
			)
			(layer "F.SilkS")
		)
		(fp_line
			(start -0.7874 0.4064)
			(end -0.7874 -0.4064)
			(stroke
				(width 0.1524)
				(type default)
			)
			(layer "F.SilkS")
		)
		(fp_line
			(start -0.7874 -0.4064)
			(end 0.7874 -0.4064)
			(stroke
				(width 0.1524)
				(type default)
			)
			(layer "F.SilkS")
		)
		(fp_line
			(start 0.67945 0.3048)
			(end 0.120396 0.3048)
			(stroke
				(width 0.1)
				(type default)
			)
			(layer "F.Fab")
		)
		(fp_line
			(start 0.67945 -0.3048)
			(end 0.67945 0.3048)
			(stroke
				(width 0.1)
				(type default)
			)
			(layer "F.Fab")
		)
		(fp_line
			(start 0.12065 -0.2794)
			(end 0.12065 -0.3048)
			(stroke
				(width 0.1)
				(type default)
			)
			(layer "F.Fab")
		)
		(fp_line
			(start 0.12065 -0.3048)
			(end 0.67945 -0.3048)
			(stroke
				(width 0.1)
				(type default)
			)
			(layer "F.Fab")
		)
		(fp_line
			(start 0.120396 0.3048)
			(end 0.120396 0.2794)
			(stroke
				(width 0.1)
				(type default)
			)
			(layer "F.Fab")
		)
		(fp_line
			(start 0.120396 0.2794)
			(end -0.12065 0.2794)
			(stroke
				(width 0.1)
				(type default)
			)
			(layer "F.Fab")
		)
		(fp_line
			(start -0.12065 0.3048)
			(end -0.67945 0.3048)
			(stroke
				(width 0.1)
				(type default)
			)
			(layer "F.Fab")
		)
		(fp_line
			(start -0.12065 0.2794)
			(end -0.12065 0.3048)
			(stroke
				(width 0.1)
				(type default)
			)
			(layer "F.Fab")
		)
		(fp_line
			(start -0.12065 -0.2794)
			(end 0.12065 -0.2794)
			(stroke
				(width 0.1)
				(type default)
			)
			(layer "F.Fab")
		)
		(fp_line
			(start -0.12065 -0.305054)
			(end -0.12065 -0.2794)
			(stroke
				(width 0.1)
				(type default)
			)
			(layer "F.Fab")
		)
		(fp_line
			(start -0.67945 0.3048)
			(end -0.67945 -0.305054)
			(stroke
				(width 0.1)
				(type default)
			)
			(layer "F.Fab")
		)
		(fp_line
			(start -0.67945 -0.305054)
			(end -0.12065 -0.305054)
			(stroke
				(width 0.1)
				(type default)
			)
			(layer "F.Fab")
		)
		(pad "1" smd circle
			(at -0.40005 0 180)
			(size 0 0)
			(layers "F.Cu" "F.Mask" "F.Paste")
			(net "E1S_0_P12V_EN")
		)
		(pad "2" smd circle
			(at 0.40005 0 180)
			(size 0 0)
			(layers "F.Cu" "F.Mask" "F.Paste")
			(net "P12V_E1S_0_EN")
		)
	)
	(footprint ""
		(layer "F.Cu")
		(at 190.5 -44.577 180)
		(property "Reference" "R8024"
			(at 0 0 180)
			(layer "F.SilkS")
			(hide yes)
			(effects
				(font
					(size 1.27 1.27)
				)
			)
		)
		(property "Value" ""
			(at 0 0 180)
			(layer "F.Fab")
			(effects
				(font
					(size 1.27 1.27)
				)
			)
		)
		(duplicate_pad_numbers_are_jumpers no)
		(fp_line
			(start 0.7874 0.4064)
			(end -0.7874 0.4064)
			(stroke
				(width 0.1524)
				(type default)
			)
			(layer "F.SilkS")
		)
		(fp_line
			(start 0.7874 -0.4064)
			(end 0.7874 0.4064)
			(stroke
				(width 0.1524)
				(type default)
			)
			(layer "F.SilkS")
		)
		(fp_line
			(start -0.7874 0.4064)
			(end -0.7874 -0.4064)
			(stroke
				(width 0.1524)
				(type default)
			)
			(layer "F.SilkS")
		)
		(fp_line
			(start -0.7874 -0.4064)
			(end 0.7874 -0.4064)
			(stroke
				(width 0.1524)
				(type default)
			)
			(layer "F.SilkS")
		)
		(fp_line
			(start 0.67945 0.3048)
			(end 0.120396 0.3048)
			(stroke
				(width 0.1)
				(type default)
			)
			(layer "F.Fab")
		)
		(fp_line
			(start 0.67945 -0.3048)
			(end 0.67945 0.3048)
			(stroke
				(width 0.1)
				(type default)
			)
			(layer "F.Fab")
		)
		(fp_line
			(start 0.12065 -0.2794)
			(end 0.12065 -0.3048)
			(stroke
				(width 0.1)
				(type default)
			)
			(layer "F.Fab")
		)
		(fp_line
			(start 0.12065 -0.3048)
			(end 0.67945 -0.3048)
			(stroke
				(width 0.1)
				(type default)
			)
			(layer "F.Fab")
		)
		(fp_line
			(start 0.120396 0.3048)
			(end 0.120396 0.2794)
			(stroke
				(width 0.1)
				(type default)
			)
			(layer "F.Fab")
		)
		(fp_line
			(start 0.120396 0.2794)
			(end -0.12065 0.2794)
			(stroke
				(width 0.1)
				(type default)
			)
			(layer "F.Fab")
		)
		(fp_line
			(start -0.12065 0.3048)
			(end -0.67945 0.3048)
			(stroke
				(width 0.1)
				(type default)
			)
			(layer "F.Fab")
		)
		(fp_line
			(start -0.12065 0.2794)
			(end -0.12065 0.3048)
			(stroke
				(width 0.1)
				(type default)
			)
			(layer "F.Fab")
		)
		(fp_line
			(start -0.12065 -0.2794)
			(end 0.12065 -0.2794)
			(stroke
				(width 0.1)
				(type default)
			)
			(layer "F.Fab")
		)
		(fp_line
			(start -0.12065 -0.305054)
			(end -0.12065 -0.2794)
			(stroke
				(width 0.1)
				(type default)
			)
			(layer "F.Fab")
		)
		(fp_line
			(start -0.67945 0.3048)
			(end -0.67945 -0.305054)
			(stroke
				(width 0.1)
				(type default)
			)
			(layer "F.Fab")
		)
		(fp_line
			(start -0.67945 -0.305054)
			(end -0.12065 -0.305054)
			(stroke
				(width 0.1)
				(type default)
			)
			(layer "F.Fab")
		)
		(pad "1" smd circle
			(at -0.40005 0 180)
			(size 0 0)
			(layers "F.Cu" "F.Mask" "F.Paste")
			(net "LED_P12V_AUX_R3")
		)
		(pad "2" smd circle
			(at 0.40005 0 180)
			(size 0 0)
			(layers "F.Cu" "F.Mask" "F.Paste")
			(net "P12V_AUX")
		)
	)
)
